(kicad_pcb
	(version 20260206)
	(generator "pcbnew")
	(generator_version "10.0")
	(general
		(thickness 1.6)
		(legacy_teardrops no)
	)
	(paper "A4")
	(title_block
		(title "peb — Lightning_PEB_BRD.brd")
		(comment 1 "Lightning (Wiwynn / Facebook NVMe JBOF) / footprints 448-455 of 2563")
	)
	(layers
		(0 "F.Cu" signal "TOP")
		(4 "In1.Cu" signal "L2GND")
		(6 "In2.Cu" signal "L3")
		(8 "In3.Cu" signal "L4VCC")
		(10 "In4.Cu" signal "L5VCC")
		(12 "In5.Cu" signal "L6")
		(14 "In6.Cu" signal "L7GND")
		(2 "B.Cu" signal "BOTTOM")
		(9 "F.Adhes" user "F.Adhesive")
		(11 "B.Adhes" user "B.Adhesive")
		(13 "F.Paste" user "Package Geometry/Pastemask Top")
		(15 "B.Paste" user "Package Geometry/Pastemask Bottom")
		(5 "F.SilkS" user "Ref Des/Silkscreen Top")
		(7 "B.SilkS" user "Ref Des/Silkscreen Bottom")
		(1 "F.Mask" user "Board Geometry/Soldermask Top")
		(3 "B.Mask" user "Board Geometry/Soldermask Bottom")
		(17 "Dwgs.User" user "User.Drawings")
		(19 "Cmts.User" user "User.Comments")
		(21 "Eco1.User" user "User.Eco1")
		(23 "Eco2.User" user "User.Eco2")
		(25 "Edge.Cuts" user "Board Geometry/Outline")
		(27 "Margin" user)
		(31 "F.CrtYd" user "Package Geometry/Place Bound Top")
		(29 "B.CrtYd" user "Package Geometry/Place Bound Bottom")
		(35 "F.Fab" user "Ref Des/Assembly Top")
		(33 "B.Fab" user "Ref Des/Assembly Bottom")
	)
	(footprint ""
		(layer "F.Cu")
		(at 128.509268 -33.158938 90)
		(property "Reference" "R633"
			(at 0 0 90)
			(layer "F.SilkS")
			(hide yes)
			(effects
				(font
					(size 1.27 1.27)
				)
			)
		)
		(property "Value" "0R2J-2-GP"
			(at 0.064008 -3.993896 90)
			(unlocked yes)
			(layer "F.Fab")
			(hide yes)
			(effects
				(font
					(size 1.016 1.016)
					(thickness 0.1524)
				)
			)
		)
		(property "Device Type" "R402H16"
			(at 0.064008 -5.517896 90)
			(unlocked yes)
			(layer "F.Fab")
			(hide yes)
			(effects
				(font
					(size 1.016 1.016)
					(thickness 0.1524)
				)
			)
		)
		(duplicate_pad_numbers_are_jumpers no)
		(fp_line
			(start 0.508 -0.9398)
			(end -0.508 -0.9398)
			(stroke
				(width 0.1524)
				(type default)
			)
			(layer "F.SilkS")
		)
		(fp_line
			(start -0.508 -0.9398)
			(end -0.508 0.9398)
			(stroke
				(width 0.1524)
				(type default)
			)
			(layer "F.SilkS")
		)
		(fp_rect
			(start -0.508 0.9398)
			(end 0.508 -0.9398)
			(stroke
				(width 0)
				(type default)
			)
			(fill no)
			(layer "F.CrtYd")
		)
		(fp_rect
			(start -0.508 0.9398)
			(end 0.508 -0.9398)
			(stroke
				(width 0)
				(type default)
			)
			(fill no)
			(layer "F.Fab")
		)
		(pad "1" smd custom
			(at 0 -0.4445 90)
			(size 0.1397 0.1397)
			(layers "F.Cu" "F.Mask" "F.Paste")
			(net "8644_USB_DP1")
			(options
				(clearance outline)
				(anchor circle)
			)
			(primitives
				(gr_poly
					(pts
						(arc
							(start -0.1778 -0.2794)
							(mid -0.249642 -0.249642)
							(end -0.2794 -0.1778)
						)
						(arc
							(start -0.2794 0.1778)
							(mid -0.249642 0.249642)
							(end -0.1778 0.2794)
						)
						(arc
							(start 0.1778 0.2794)
							(mid 0.249642 0.249642)
							(end 0.2794 0.1778)
						)
						(arc
							(start 0.2794 -0.1778)
							(mid 0.249642 -0.249642)
							(end 0.1778 -0.2794)
						)
					)
					(width 0)
					(fill yes)
				)
			)
		)
		(pad "2" smd custom
			(at 0 0.4445 90)
			(size 0.1397 0.1397)
			(layers "F.Cu" "F.Mask" "F.Paste")
			(net "P3V3_STBY")
			(options
				(clearance outline)
				(anchor circle)
			)
			(primitives
				(gr_poly
					(pts
						(arc
							(start -0.1778 -0.2794)
							(mid -0.249642 -0.249642)
							(end -0.2794 -0.1778)
						)
						(arc
							(start -0.2794 0.1778)
							(mid -0.249642 0.249642)
							(end -0.1778 0.2794)
						)
						(arc
							(start 0.1778 0.2794)
							(mid 0.249642 0.249642)
							(end 0.2794 0.1778)
						)
						(arc
							(start 0.2794 -0.1778)
							(mid 0.249642 -0.249642)
							(end 0.1778 -0.2794)
						)
					)
					(width 0)
					(fill yes)
				)
			)
		)
	)
	(footprint ""
		(layer "F.Cu")
		(at 148.098002 -58.066432 90)
		(property "Reference" "PR170"
			(at 0 0 90)
			(layer "F.SilkS")
			(hide yes)
			(effects
				(font
					(size 1.27 1.27)
				)
			)
		)
		(property "Value" "475KR2F-GP"
			(at 0.064008 -3.993896 90)
			(unlocked yes)
			(layer "F.Fab")
			(hide yes)
			(effects
				(font
					(size 1.016 1.016)
					(thickness 0.1524)
				)
			)
		)
		(property "Device Type" "R402H16"
			(at 0.064008 -5.517896 90)
			(unlocked yes)
			(layer "F.Fab")
			(hide yes)
			(effects
				(font
					(size 1.016 1.016)
					(thickness 0.1524)
				)
			)
		)
		(duplicate_pad_numbers_are_jumpers no)
		(fp_line
			(start 0.508 -0.9398)
			(end -0.508 -0.9398)
			(stroke
				(width 0.1524)
				(type default)
			)
			(layer "F.SilkS")
		)
		(fp_line
			(start -0.508 -0.9398)
			(end -0.508 0.9398)
			(stroke
				(width 0.1524)
				(type default)
			)
			(layer "F.SilkS")
		)
		(fp_rect
			(start -0.508 0.9398)
			(end 0.508 -0.9398)
			(stroke
				(width 0)
				(type default)
			)
			(fill no)
			(layer "F.CrtYd")
		)
		(fp_rect
			(start -0.508 0.9398)
			(end 0.508 -0.9398)
			(stroke
				(width 0)
				(type default)
			)
			(fill no)
			(layer "F.Fab")
		)
		(pad "1" smd custom
			(at 0 -0.4445 90)
			(size 0.1397 0.1397)
			(layers "F.Cu" "F.Mask" "F.Paste")
			(net "P0V9_PG")
			(options
				(clearance outline)
				(anchor circle)
			)
			(primitives
				(gr_poly
					(pts
						(arc
							(start -0.1778 -0.2794)
							(mid -0.249642 -0.249642)
							(end -0.2794 -0.1778)
						)
						(arc
							(start -0.2794 0.1778)
							(mid -0.249642 0.249642)
							(end -0.1778 0.2794)
						)
						(arc
							(start 0.1778 0.2794)
							(mid 0.249642 0.249642)
							(end 0.2794 0.1778)
						)
						(arc
							(start 0.2794 -0.1778)
							(mid 0.249642 -0.249642)
							(end 0.1778 -0.2794)
						)
					)
					(width 0)
					(fill yes)
				)
			)
		)
		(pad "2" smd custom
			(at 0 0.4445 90)
			(size 0.1397 0.1397)
			(layers "F.Cu" "F.Mask" "F.Paste")
			(net "P0V9_MODE")
			(options
				(clearance outline)
				(anchor circle)
			)
			(primitives
				(gr_poly
					(pts
						(arc
							(start -0.1778 -0.2794)
							(mid -0.249642 -0.249642)
							(end -0.2794 -0.1778)
						)
						(arc
							(start -0.2794 0.1778)
							(mid -0.249642 0.249642)
							(end -0.1778 0.2794)
						)
						(arc
							(start 0.1778 0.2794)
							(mid 0.249642 0.249642)
							(end 0.2794 0.1778)
						)
						(arc
							(start 0.2794 -0.1778)
							(mid 0.249642 -0.249642)
							(end 0.1778 -0.2794)
						)
					)
					(width 0)
					(fill yes)
				)
			)
		)
	)
	(footprint ""
		(layer "F.Cu")
		(at 31.369 -46.99 -90)
		(property "Reference" "C338"
			(at 0 0 270)
			(layer "F.SilkS")
			(hide yes)
			(effects
				(font
					(size 1.27 1.27)
				)
			)
		)
		(property "Value" "SC1U10V2KX-4-GP"
			(at 1.1811 -2.7051 270)
			(unlocked yes)
			(layer "F.Fab")
			(hide yes)
			(effects
				(font
					(size 1.016 1.016)
					(thickness 0.1524)
				)
			)
		)
		(property "Device Type" "C402H22"
			(at 1.1811 -4.2291 270)
			(unlocked yes)
			(layer "F.Fab")
			(hide yes)
			(effects
				(font
					(size 1.016 1.016)
					(thickness 0.1524)
				)
			)
		)
		(duplicate_pad_numbers_are_jumpers no)
		(fp_rect
			(start -0.4318 0.9525)
			(end 0.4318 -0.9525)
			(stroke
				(width 0)
				(type default)
			)
			(fill no)
			(layer "F.CrtYd")
		)
		(fp_rect
			(start -0.4318 0.9525)
			(end 0.4318 -0.9525)
			(stroke
				(width 0)
				(type default)
			)
			(fill no)
			(layer "F.Fab")
		)
		(pad "1" smd custom
			(at 0 -0.4445 270)
			(size 0.1524 0.1524)
			(layers "F.Cu" "F.Mask" "F.Paste")
			(net "P5V_USB")
			(options
				(clearance outline)
				(anchor circle)
			)
			(primitives
				(gr_poly
					(pts
						(arc
							(start 0.3048 -0.2032)
							(mid 0.275042 -0.275042)
							(end 0.2032 -0.3048)
						)
						(arc
							(start -0.2032 -0.3048)
							(mid -0.275042 -0.275042)
							(end -0.3048 -0.2032)
						)
						(arc
							(start -0.3048 0.2032)
							(mid -0.275042 0.275042)
							(end -0.2032 0.3048)
						)
						(arc
							(start 0.2032 0.3048)
							(mid 0.275042 0.275042)
							(end 0.3048 0.2032)
						)
					)
					(width 0)
					(fill yes)
				)
			)
		)
		(pad "2" smd custom
			(at 0 0.4445 270)
			(size 0.1524 0.1524)
			(layers "F.Cu" "F.Mask" "F.Paste")
			(net "GND")
			(options
				(clearance outline)
				(anchor circle)
			)
			(primitives
				(gr_poly
					(pts
						(arc
							(start 0.3048 -0.2032)
							(mid 0.275042 -0.275042)
							(end 0.2032 -0.3048)
						)
						(arc
							(start -0.2032 -0.3048)
							(mid -0.275042 -0.275042)
							(end -0.3048 -0.2032)
						)
						(arc
							(start -0.3048 0.2032)
							(mid -0.275042 0.275042)
							(end -0.2032 0.3048)
						)
						(arc
							(start 0.2032 0.3048)
							(mid 0.275042 0.275042)
							(end 0.3048 0.2032)
						)
					)
					(width 0)
					(fill yes)
				)
			)
		)
	)
	(footprint ""
		(layer "F.Cu")
		(at 41.7068 -190.2206 -90)
		(property "Reference" "C691"
			(at 0 0 270)
			(layer "F.SilkS")
			(hide yes)
			(effects
				(font
					(size 1.27 1.27)
				)
			)
		)
		(property "Value" "SC220P50V3JN-GP"
			(at 0 -2.8194 270)
			(unlocked yes)
			(layer "F.Fab")
			(hide yes)
			(effects
				(font
					(size 1.016 1.016)
					(thickness 0.1524)
				)
			)
		)
		(property "Device Type" "C603H36"
			(at 0 -4.3434 270)
			(unlocked yes)
			(layer "F.Fab")
			(hide yes)
			(effects
				(font
					(size 1.016 1.016)
					(thickness 0.1524)
				)
			)
		)
		(duplicate_pad_numbers_are_jumpers no)
		(fp_line
			(start 0.508 0)
			(end -0.508 0)
			(stroke
				(width 0.2032)
				(type default)
			)
			(layer "F.SilkS")
		)
		(fp_rect
			(start -0.5842 1.3335)
			(end 0.5842 -1.3335)
			(stroke
				(width 0)
				(type default)
			)
			(fill no)
			(layer "F.CrtYd")
		)
		(fp_rect
			(start -0.5842 1.3335)
			(end 0.5842 -1.3335)
			(stroke
				(width 0)
				(type default)
			)
			(fill no)
			(layer "F.Fab")
		)
		(pad "1" smd custom
			(at 0 -0.762 270)
			(size 0.2159 0.2159)
			(layers "F.Cu" "F.Mask" "F.Paste")
			(net "BUF_I2C9_CLKBUF2_SDA_R")
			(options
				(clearance outline)
				(anchor circle)
			)
			(primitives
				(gr_poly
					(pts
						(arc
							(start -0.3302 -0.4318)
							(mid -0.402042 -0.402042)
							(end -0.4318 -0.3302)
						)
						(arc
							(start -0.4318 0.3302)
							(mid -0.402042 0.402042)
							(end -0.3302 0.4318)
						)
						(arc
							(start 0.3302 0.4318)
							(mid 0.402042 0.402042)
							(end 0.4318 0.3302)
						)
						(arc
							(start 0.4318 -0.3302)
							(mid 0.402042 -0.402042)
							(end 0.3302 -0.4318)
						)
					)
					(width 0)
					(fill yes)
				)
			)
		)
		(pad "2" smd custom
			(at 0 0.762 270)
			(size 0.2159 0.2159)
			(layers "F.Cu" "F.Mask" "F.Paste")
			(net "GND")
			(options
				(clearance outline)
				(anchor circle)
			)
			(primitives
				(gr_poly
					(pts
						(arc
							(start -0.3302 -0.4318)
							(mid -0.402042 -0.402042)
							(end -0.4318 -0.3302)
						)
						(arc
							(start -0.4318 0.3302)
							(mid -0.402042 0.402042)
							(end -0.3302 0.4318)
						)
						(arc
							(start 0.3302 0.4318)
							(mid 0.402042 0.402042)
							(end 0.4318 0.3302)
						)
						(arc
							(start 0.4318 -0.3302)
							(mid 0.402042 -0.402042)
							(end 0.3302 -0.4318)
						)
					)
					(width 0)
					(fill yes)
				)
			)
		)
	)
	(footprint ""
		(layer "F.Cu")
		(at 289.992054 -212.420454 180)
		(property "Reference" "C80"
			(at 0 0 180)
			(layer "F.SilkS")
			(hide yes)
			(effects
				(font
					(size 1.27 1.27)
				)
			)
		)
		(property "Value" "SCD22U10V2KX-1GP"
			(at 1.1811 -2.7051 180)
			(unlocked yes)
			(layer "F.Fab")
			(hide yes)
			(effects
				(font
					(size 1.016 1.016)
					(thickness 0.1524)
				)
			)
		)
		(property "Device Type" "C402H22"
			(at 1.1811 -4.2291 180)
			(unlocked yes)
			(layer "F.Fab")
			(hide yes)
			(effects
				(font
					(size 1.016 1.016)
					(thickness 0.1524)
				)
			)
		)
		(duplicate_pad_numbers_are_jumpers no)
		(fp_rect
			(start -0.4318 0.9525)
			(end 0.4318 -0.9525)
			(stroke
				(width 0)
				(type default)
			)
			(fill no)
			(layer "F.CrtYd")
		)
		(fp_rect
			(start -0.4318 0.9525)
			(end 0.4318 -0.9525)
			(stroke
				(width 0)
				(type default)
			)
			(fill no)
			(layer "F.Fab")
		)
		(pad "1" smd custom
			(at 0 -0.4445 180)
			(size 0.1524 0.1524)
			(layers "F.Cu" "F.Mask" "F.Paste")
			(net "PCIE_TX_CAP_P29")
			(options
				(clearance outline)
				(anchor circle)
			)
			(primitives
				(gr_poly
					(pts
						(arc
							(start 0.3048 -0.2032)
							(mid 0.275042 -0.275042)
							(end 0.2032 -0.3048)
						)
						(arc
							(start -0.2032 -0.3048)
							(mid -0.275042 -0.275042)
							(end -0.3048 -0.2032)
						)
						(arc
							(start -0.3048 0.2032)
							(mid -0.275042 0.275042)
							(end -0.2032 0.3048)
						)
						(arc
							(start 0.2032 0.3048)
							(mid 0.275042 0.275042)
							(end 0.3048 0.2032)
						)
					)
					(width 0)
					(fill yes)
				)
			)
		)
		(pad "2" smd custom
			(at 0 0.4445 180)
			(size 0.1524 0.1524)
			(layers "F.Cu" "F.Mask" "F.Paste")
			(net "PCIE_TX_P29")
			(options
				(clearance outline)
				(anchor circle)
			)
			(primitives
				(gr_poly
					(pts
						(arc
							(start 0.3048 -0.2032)
							(mid 0.275042 -0.275042)
							(end 0.2032 -0.3048)
						)
						(arc
							(start -0.2032 -0.3048)
							(mid -0.275042 -0.275042)
							(end -0.3048 -0.2032)
						)
						(arc
							(start -0.3048 0.2032)
							(mid -0.275042 0.275042)
							(end -0.2032 0.3048)
						)
						(arc
							(start 0.2032 0.3048)
							(mid 0.275042 0.275042)
							(end 0.3048 0.2032)
						)
					)
					(width 0)
					(fill yes)
				)
			)
		)
	)
	(footprint ""
		(layer "F.Cu")
		(at 64.607948 -212.420454 180)
		(property "Reference" "C358"
			(at 0 0 180)
			(layer "F.SilkS")
			(hide yes)
			(effects
				(font
					(size 1.27 1.27)
				)
			)
		)
		(property "Value" "SCD22U10V2KX-1GP"
			(at 1.1811 -2.7051 180)
			(unlocked yes)
			(layer "F.Fab")
			(hide yes)
			(effects
				(font
					(size 1.016 1.016)
					(thickness 0.1524)
				)
			)
		)
		(property "Device Type" "C402H22"
			(at 1.1811 -4.2291 180)
			(unlocked yes)
			(layer "F.Fab")
			(hide yes)
			(effects
				(font
					(size 1.016 1.016)
					(thickness 0.1524)
				)
			)
		)
		(duplicate_pad_numbers_are_jumpers no)
		(fp_rect
			(start -0.4318 0.9525)
			(end 0.4318 -0.9525)
			(stroke
				(width 0)
				(type default)
			)
			(fill no)
			(layer "F.CrtYd")
		)
		(fp_rect
			(start -0.4318 0.9525)
			(end 0.4318 -0.9525)
			(stroke
				(width 0)
				(type default)
			)
			(fill no)
			(layer "F.Fab")
		)
		(pad "1" smd custom
			(at 0 -0.4445 180)
			(size 0.1524 0.1524)
			(layers "F.Cu" "F.Mask" "F.Paste")
			(net "PCIE_TX_CAP_N71")
			(options
				(clearance outline)
				(anchor circle)
			)
			(primitives
				(gr_poly
					(pts
						(arc
							(start 0.3048 -0.2032)
							(mid 0.275042 -0.275042)
							(end 0.2032 -0.3048)
						)
						(arc
							(start -0.2032 -0.3048)
							(mid -0.275042 -0.275042)
							(end -0.3048 -0.2032)
						)
						(arc
							(start -0.3048 0.2032)
							(mid -0.275042 0.275042)
							(end -0.2032 0.3048)
						)
						(arc
							(start 0.2032 0.3048)
							(mid 0.275042 0.275042)
							(end 0.3048 0.2032)
						)
					)
					(width 0)
					(fill yes)
				)
			)
		)
		(pad "2" smd custom
			(at 0 0.4445 180)
			(size 0.1524 0.1524)
			(layers "F.Cu" "F.Mask" "F.Paste")
			(net "PCIE_TX_N71")
			(options
				(clearance outline)
				(anchor circle)
			)
			(primitives
				(gr_poly
					(pts
						(arc
							(start 0.3048 -0.2032)
							(mid 0.275042 -0.275042)
							(end 0.2032 -0.3048)
						)
						(arc
							(start -0.2032 -0.3048)
							(mid -0.275042 -0.275042)
							(end -0.3048 -0.2032)
						)
						(arc
							(start -0.3048 0.2032)
							(mid -0.275042 0.275042)
							(end -0.2032 0.3048)
						)
						(arc
							(start 0.2032 0.3048)
							(mid 0.275042 0.275042)
							(end 0.3048 0.2032)
						)
					)
					(width 0)
					(fill yes)
				)
			)
		)
	)
	(footprint ""
		(layer "F.Cu")
		(at 184.0484 -61.595)
		(property "Reference" "C564"
			(at 0 0 0)
			(layer "F.SilkS")
			(hide yes)
			(effects
				(font
					(size 1.27 1.27)
				)
			)
		)
		(property "Value" "SC4D7U16V5KX-1-GP"
			(at -0.0762 -6.1214 0)
			(unlocked yes)
			(layer "F.Fab")
			(hide yes)
			(effects
				(font
					(size 1.016 1.016)
					(thickness 0.1524)
				)
			)
		)
		(property "Device Type" "C805H56"
			(at -0.0762 -8.1534 0)
			(unlocked yes)
			(layer "F.Fab")
			(hide yes)
			(effects
				(font
					(size 1.016 1.016)
					(thickness 0.1524)
				)
			)
		)
		(duplicate_pad_numbers_are_jumpers no)
		(fp_line
			(start 0.635 0)
			(end -0.635 0)
			(stroke
				(width 0.508)
				(type default)
			)
			(layer "F.SilkS")
		)
		(fp_rect
			(start -0.9652 1.778)
			(end 0.9652 -1.778)
			(stroke
				(width 0)
				(type default)
			)
			(fill no)
			(layer "F.CrtYd")
		)
		(fp_poly
			(pts
				(xy -0.9652 -1.778) (xy 0.9652 -1.778) (xy 0.9652 1.778) (xy -0.9652 1.778)
			)
			(stroke
				(width 0)
				(type default)
			)
			(fill no)
			(layer "F.Fab")
		)
		(pad "1" smd rect
			(at 0 -0.9652)
			(size 1.397 1.143)
			(layers "F.Cu" "F.Mask" "F.Paste")
			(net "DUT_AVD_PCIE")
		)
		(pad "2" smd rect
			(at 0 0.9652)
			(size 1.397 1.143)
			(layers "F.Cu" "F.Mask" "F.Paste")
			(net "GND")
		)
	)
	(footprint ""
		(layer "F.Cu")
		(at 65.405 -133.985 180)
		(property "Reference" "R3029"
			(at 0 0 180)
			(layer "F.SilkS")
			(hide yes)
			(effects
				(font
					(size 1.27 1.27)
				)
			)
		)
		(property "Value" "1KR2F-3-GP"
			(at 0.064008 -3.993896 180)
			(unlocked yes)
			(layer "F.Fab")
			(hide yes)
			(effects
				(font
					(size 1.016 1.016)
					(thickness 0.1524)
				)
			)
		)
		(property "Device Type" "R402H16"
			(at 0.064008 -5.517896 180)
			(unlocked yes)
			(layer "F.Fab")
			(hide yes)
			(effects
				(font
					(size 1.016 1.016)
					(thickness 0.1524)
				)
			)
		)
		(duplicate_pad_numbers_are_jumpers no)
		(fp_line
			(start 0.508 -0.9398)
			(end -0.508 -0.9398)
			(stroke
				(width 0.1524)
				(type default)
			)
			(layer "F.SilkS")
		)
		(fp_line
			(start -0.508 -0.9398)
			(end -0.508 0.9398)
			(stroke
				(width 0.1524)
				(type default)
			)
			(layer "F.SilkS")
		)
		(fp_rect
			(start -0.508 0.9398)
			(end 0.508 -0.9398)
			(stroke
				(width 0)
				(type default)
			)
			(fill no)
			(layer "F.CrtYd")
		)
		(fp_rect
			(start -0.508 0.9398)
			(end 0.508 -0.9398)
			(stroke
				(width 0)
				(type default)
			)
			(fill no)
			(layer "F.Fab")
		)
		(pad "1" smd custom
			(at 0 -0.4445 180)
			(size 0.1397 0.1397)
			(layers "F.Cu" "F.Mask" "F.Paste")
			(net "P0V9")
			(options
				(clearance outline)
				(anchor circle)
			)
			(primitives
				(gr_poly
					(pts
						(arc
							(start -0.1778 -0.2794)
							(mid -0.249642 -0.249642)
							(end -0.2794 -0.1778)
						)
						(arc
							(start -0.2794 0.1778)
							(mid -0.249642 0.249642)
							(end -0.1778 0.2794)
						)
						(arc
							(start 0.1778 0.2794)
							(mid 0.249642 0.249642)
							(end 0.2794 0.1778)
						)
						(arc
							(start 0.2794 -0.1778)
							(mid 0.249642 -0.249642)
							(end 0.1778 -0.2794)
						)
					)
					(width 0)
					(fill yes)
				)
			)
		)
		(pad "2" smd custom
			(at 0 0.4445 180)
			(size 0.1397 0.1397)
			(layers "F.Cu" "F.Mask" "F.Paste")
			(net "ADC_P0V9")
			(options
				(clearance outline)
				(anchor circle)
			)
			(primitives
				(gr_poly
					(pts
						(arc
							(start -0.1778 -0.2794)
							(mid -0.249642 -0.249642)
							(end -0.2794 -0.1778)
						)
						(arc
							(start -0.2794 0.1778)
							(mid -0.249642 0.249642)
							(end -0.1778 0.2794)
						)
						(arc
							(start 0.1778 0.2794)
							(mid 0.249642 0.249642)
							(end 0.2794 0.1778)
						)
						(arc
							(start 0.2794 -0.1778)
							(mid 0.249642 -0.249642)
							(end 0.1778 -0.2794)
						)
					)
					(width 0)
					(fill yes)
				)
			)
		)
	)
)
